(kicad_pcb
	(version 20260206)
	(generator "pcbnew")
	(generator_version "10.0")
	(general
		(thickness 1.6)
		(legacy_teardrops no)
	)
	(paper "A4")
	(title_block
		(title "04192023_DAF0TMB3IC0_F0TG_MB_C_brd_V02_OCP.brd")
		(comment 1 "Grand Teton / footprint 1120 of 8354 (J15), pads 114-226 of 291")
	)
	(layers
		(0 "F.Cu" signal "TOP")
		(4 "In1.Cu" signal "GND")
		(6 "In2.Cu" signal "IN1")
		(8 "In3.Cu" signal "GND1")
		(10 "In4.Cu" signal "IN2")
		(12 "In5.Cu" signal "GND2")
		(14 "In6.Cu" signal "IN3")
		(16 "In7.Cu" signal "GND3")
		(18 "In8.Cu" signal "VCC")
		(20 "In9.Cu" signal "VCC1")
		(22 "In10.Cu" signal "GND4")
		(24 "In11.Cu" signal "IN4")
		(26 "In12.Cu" signal "GND5")
		(28 "In13.Cu" signal "IN5")
		(30 "In14.Cu" signal "GND6")
		(32 "In15.Cu" signal "IN6")
		(34 "In16.Cu" signal "GND7")
		(2 "B.Cu" signal "BOTTOM")
		(9 "F.Adhes" user "F.Adhesive")
		(11 "B.Adhes" user "B.Adhesive")
		(13 "F.Paste" user "Package Geometry/Pastemask Top")
		(15 "B.Paste" user "Package Geometry/Pastemask Bottom")
		(5 "F.SilkS" user "Ref Des/Silkscreen Top")
		(7 "B.SilkS" user "Ref Des/Silkscreen Bottom")
		(1 "F.Mask" user "Board Geometry/Soldermask Top")
		(3 "B.Mask" user "Board Geometry/Soldermask Bottom")
		(17 "Dwgs.User" user "User.Drawings")
		(19 "Cmts.User" user "User.Comments")
		(21 "Eco1.User" user "User.Eco1")
		(23 "Eco2.User" user "User.Eco2")
		(25 "Edge.Cuts" user "Board Geometry/Outline")
		(27 "Margin" user)
		(31 "F.CrtYd" user "Package Geometry/Place Bound Top")
		(29 "B.CrtYd" user "Package Geometry/Place Bound Bottom")
		(35 "F.Fab" user "Ref Des/Assembly Top")
		(33 "B.Fab" user "Ref Des/Assembly Bottom")
	)
	(footprint ""
		(layer "F.Cu")
		(at 297.774106 -255.560068 180)
		(property "Reference" "J15"
			(at -2.2098 -81.984088 0)
			(unlocked yes)
			(layer "F.SilkS")
			(effects
				(font
					(size 0.7874 0.5842)
					(thickness 0.1524)
				)
			)
		)
		(property "Value" ""
			(at 0 0 180)
			(layer "F.Fab")
			(effects
				(font
					(size 1.27 1.27)
				)
			)
		)
		(duplicate_pad_numbers_are_jumpers no)
		(pad "114" smd rect
			(at -2.050034 37.824918 90)
			(size 0.519938 1.4986)
			(layers "F.Cu" "F.Mask" "F.Paste")
			(net "GND")
		)
		(pad "115" smd rect
			(at -2.050034 38.675056 90)
			(size 0.519938 1.4986)
			(layers "F.Cu" "F.Mask" "F.Paste")
			(net "M_B_CPU0_SB_DQS_DP<1>")
		)
		(pad "116" smd rect
			(at -2.050034 39.52494 90)
			(size 0.519938 1.4986)
			(layers "F.Cu" "F.Mask" "F.Paste")
			(net "M_B_CPU0_SB_DQS_DN<1>")
		)
		(pad "117" smd rect
			(at -2.050034 40.375078 90)
			(size 0.519938 1.4986)
			(layers "F.Cu" "F.Mask" "F.Paste")
			(net "GND")
		)
		(pad "118" smd rect
			(at -2.050034 41.224962 90)
			(size 0.519938 1.4986)
			(layers "F.Cu" "F.Mask" "F.Paste")
			(net "M_B_CPU0_SB_DQ<12>")
		)
		(pad "119" smd rect
			(at -2.050034 42.0751 90)
			(size 0.519938 1.4986)
			(layers "F.Cu" "F.Mask" "F.Paste")
			(net "GND")
		)
		(pad "120" smd rect
			(at -2.050034 42.924984 90)
			(size 0.519938 1.4986)
			(layers "F.Cu" "F.Mask" "F.Paste")
			(net "M_B_CPU0_SB_DQ<13>")
		)
		(pad "121" smd rect
			(at -2.050034 43.775122 90)
			(size 0.519938 1.4986)
			(layers "F.Cu" "F.Mask" "F.Paste")
			(net "GND")
		)
		(pad "122" smd rect
			(at -2.050034 44.625006 90)
			(size 0.519938 1.4986)
			(layers "F.Cu" "F.Mask" "F.Paste")
			(net "M_B_CPU0_SB_DQ<16>")
		)
		(pad "123" smd rect
			(at -2.050034 45.47489 90)
			(size 0.519938 1.4986)
			(layers "F.Cu" "F.Mask" "F.Paste")
			(net "GND")
		)
		(pad "124" smd rect
			(at -2.050034 46.325028 90)
			(size 0.519938 1.4986)
			(layers "F.Cu" "F.Mask" "F.Paste")
			(net "M_B_CPU0_SB_DQ<17>")
		)
		(pad "125" smd rect
			(at -2.050034 47.174912 90)
			(size 0.519938 1.4986)
			(layers "F.Cu" "F.Mask" "F.Paste")
			(net "GND")
		)
		(pad "126" smd rect
			(at -2.050034 48.02505 90)
			(size 0.519938 1.4986)
			(layers "F.Cu" "F.Mask" "F.Paste")
			(net "M_B_CPU0_SB_DQS_DP<2>")
		)
		(pad "127" smd rect
			(at -2.050034 48.874934 90)
			(size 0.519938 1.4986)
			(layers "F.Cu" "F.Mask" "F.Paste")
			(net "M_B_CPU0_SB_DQS_DN<2>")
		)
		(pad "128" smd rect
			(at -2.050034 49.725072 90)
			(size 0.519938 1.4986)
			(layers "F.Cu" "F.Mask" "F.Paste")
			(net "GND")
		)
		(pad "129" smd rect
			(at -2.050034 50.574956 90)
			(size 0.519938 1.4986)
			(layers "F.Cu" "F.Mask" "F.Paste")
			(net "M_B_CPU0_SB_DQ<20>")
		)
		(pad "130" smd rect
			(at -2.050034 51.425094 90)
			(size 0.519938 1.4986)
			(layers "F.Cu" "F.Mask" "F.Paste")
			(net "GND")
		)
		(pad "131" smd rect
			(at -2.050034 52.274978 90)
			(size 0.519938 1.4986)
			(layers "F.Cu" "F.Mask" "F.Paste")
			(net "M_B_CPU0_SB_DQ<21>")
		)
		(pad "132" smd rect
			(at -2.050034 53.125116 90)
			(size 0.519938 1.4986)
			(layers "F.Cu" "F.Mask" "F.Paste")
			(net "GND")
		)
		(pad "133" smd rect
			(at -2.050034 53.975 90)
			(size 0.519938 1.4986)
			(layers "F.Cu" "F.Mask" "F.Paste")
			(net "M_B_CPU0_SB_DQ<24>")
		)
		(pad "134" smd rect
			(at -2.050034 54.824884 90)
			(size 0.519938 1.4986)
			(layers "F.Cu" "F.Mask" "F.Paste")
			(net "GND")
		)
		(pad "135" smd rect
			(at -2.050034 55.675022 90)
			(size 0.519938 1.4986)
			(layers "F.Cu" "F.Mask" "F.Paste")
			(net "M_B_CPU0_SB_DQ<25>")
		)
		(pad "136" smd rect
			(at -2.050034 56.524906 90)
			(size 0.519938 1.4986)
			(layers "F.Cu" "F.Mask" "F.Paste")
			(net "GND")
		)
		(pad "137" smd rect
			(at -2.050034 57.375044 90)
			(size 0.519938 1.4986)
			(layers "F.Cu" "F.Mask" "F.Paste")
			(net "M_B_CPU0_SB_DQS_DP<3>")
		)
		(pad "138" smd rect
			(at -2.050034 58.224928 90)
			(size 0.519938 1.4986)
			(layers "F.Cu" "F.Mask" "F.Paste")
			(net "M_B_CPU0_SB_DQS_DN<3>")
		)
		(pad "139" smd rect
			(at -2.050034 59.075066 90)
			(size 0.519938 1.4986)
			(layers "F.Cu" "F.Mask" "F.Paste")
			(net "GND")
		)
		(pad "140" smd rect
			(at -2.050034 59.92495 90)
			(size 0.519938 1.4986)
			(layers "F.Cu" "F.Mask" "F.Paste")
			(net "M_B_CPU0_SB_DQ<28>")
		)
		(pad "141" smd rect
			(at -2.050034 60.775088 90)
			(size 0.519938 1.4986)
			(layers "F.Cu" "F.Mask" "F.Paste")
			(net "GND")
		)
		(pad "142" smd rect
			(at -2.050034 61.624972 90)
			(size 0.519938 1.4986)
			(layers "F.Cu" "F.Mask" "F.Paste")
			(net "M_B_CPU0_SB_DQ<29>")
		)
		(pad "143" smd rect
			(at -2.050034 62.47511 90)
			(size 0.519938 1.4986)
			(layers "F.Cu" "F.Mask" "F.Paste")
			(net "GND")
		)
		(pad "144" smd rect
			(at -2.050034 63.324994 90)
			(size 0.519938 1.4986)
			(layers "F.Cu" "F.Mask" "F.Paste")
			(net "Net_2264")
		)
		(pad "145" smd rect
			(at 2.050034 -63.324994 90)
			(size 0.519938 1.4986)
			(layers "F.Cu" "F.Mask" "F.Paste")
			(net "P12V_MEM_CPU0")
		)
		(pad "146" smd rect
			(at 2.050034 -62.47511 90)
			(size 0.519938 1.4986)
			(layers "F.Cu" "F.Mask" "F.Paste")
			(net "P12V_MEM_CPU0")
		)
		(pad "147" smd rect
			(at 2.050034 -61.624972 90)
			(size 0.519938 1.4986)
			(layers "F.Cu" "F.Mask" "F.Paste")
			(net "PWRGD_CHB_CPU0_DIMM")
		)
		(pad "148" smd rect
			(at 2.050034 -60.775088 90)
			(size 0.519938 1.4986)
			(layers "F.Cu" "F.Mask" "F.Paste")
			(net "PD_CHB_CPU0_DIMM_SAA")
		)
		(pad "149" smd rect
			(at 2.050034 -59.92495 90)
			(size 0.519938 1.4986)
			(layers "F.Cu" "F.Mask" "F.Paste")
			(net "Net_2265")
		)
		(pad "150" smd rect
			(at 2.050034 -59.075066 90)
			(size 0.519938 1.4986)
			(layers "F.Cu" "F.Mask" "F.Paste")
			(net "Net_2266")
		)
		(pad "151" smd rect
			(at 2.050034 -58.224928 90)
			(size 0.519938 1.4986)
			(layers "F.Cu" "F.Mask" "F.Paste")
			(net "GND")
		)
		(pad "152" smd rect
			(at 2.050034 -57.375044 90)
			(size 0.519938 1.4986)
			(layers "F.Cu" "F.Mask" "F.Paste")
			(net "M_B_CPU0_SA_DQ<2>")
		)
		(pad "153" smd rect
			(at 2.050034 -56.524906 90)
			(size 0.519938 1.4986)
			(layers "F.Cu" "F.Mask" "F.Paste")
			(net "GND")
		)
		(pad "154" smd rect
			(at 2.050034 -55.675022 90)
			(size 0.519938 1.4986)
			(layers "F.Cu" "F.Mask" "F.Paste")
			(net "M_B_CPU0_SA_DQ<3>")
		)
		(pad "155" smd rect
			(at 2.050034 -54.824884 90)
			(size 0.519938 1.4986)
			(layers "F.Cu" "F.Mask" "F.Paste")
			(net "GND")
		)
		(pad "156" smd rect
			(at 2.050034 -53.975 90)
			(size 0.519938 1.4986)
			(layers "F.Cu" "F.Mask" "F.Paste")
			(net "M_B_CPU0_SA_DQS_DN<5>")
		)
		(pad "157" smd rect
			(at 2.050034 -53.125116 90)
			(size 0.519938 1.4986)
			(layers "F.Cu" "F.Mask" "F.Paste")
			(net "M_B_CPU0_SA_DQS_DP<5>")
		)
		(pad "158" smd rect
			(at 2.050034 -52.274978 90)
			(size 0.519938 1.4986)
			(layers "F.Cu" "F.Mask" "F.Paste")
			(net "GND")
		)
		(pad "159" smd rect
			(at 2.050034 -51.425094 90)
			(size 0.519938 1.4986)
			(layers "F.Cu" "F.Mask" "F.Paste")
			(net "M_B_CPU0_SA_DQ<6>")
		)
		(pad "160" smd rect
			(at 2.050034 -50.574956 90)
			(size 0.519938 1.4986)
			(layers "F.Cu" "F.Mask" "F.Paste")
			(net "GND")
		)
		(pad "161" smd rect
			(at 2.050034 -49.725072 90)
			(size 0.519938 1.4986)
			(layers "F.Cu" "F.Mask" "F.Paste")
			(net "M_B_CPU0_SA_DQ<7>")
		)
		(pad "162" smd rect
			(at 2.050034 -48.874934 90)
			(size 0.519938 1.4986)
			(layers "F.Cu" "F.Mask" "F.Paste")
			(net "GND")
		)
		(pad "163" smd rect
			(at 2.050034 -48.02505 90)
			(size 0.519938 1.4986)
			(layers "F.Cu" "F.Mask" "F.Paste")
			(net "M_B_CPU0_SA_DQ<10>")
		)
		(pad "164" smd rect
			(at 2.050034 -47.174912 90)
			(size 0.519938 1.4986)
			(layers "F.Cu" "F.Mask" "F.Paste")
			(net "GND")
		)
		(pad "165" smd rect
			(at 2.050034 -46.325028 90)
			(size 0.519938 1.4986)
			(layers "F.Cu" "F.Mask" "F.Paste")
			(net "M_B_CPU0_SA_DQ<11>")
		)
		(pad "166" smd rect
			(at 2.050034 -45.47489 90)
			(size 0.519938 1.4986)
			(layers "F.Cu" "F.Mask" "F.Paste")
			(net "GND")
		)
		(pad "167" smd rect
			(at 2.050034 -44.625006 90)
			(size 0.519938 1.4986)
			(layers "F.Cu" "F.Mask" "F.Paste")
			(net "M_B_CPU0_SA_DQS_DN<6>")
		)
		(pad "168" smd rect
			(at 2.050034 -43.775122 90)
			(size 0.519938 1.4986)
			(layers "F.Cu" "F.Mask" "F.Paste")
			(net "M_B_CPU0_SA_DQS_DP<6>")
		)
		(pad "169" smd rect
			(at 2.050034 -42.924984 90)
			(size 0.519938 1.4986)
			(layers "F.Cu" "F.Mask" "F.Paste")
			(net "GND")
		)
		(pad "170" smd rect
			(at 2.050034 -42.0751 90)
			(size 0.519938 1.4986)
			(layers "F.Cu" "F.Mask" "F.Paste")
			(net "M_B_CPU0_SA_DQ<14>")
		)
		(pad "171" smd rect
			(at 2.050034 -41.224962 90)
			(size 0.519938 1.4986)
			(layers "F.Cu" "F.Mask" "F.Paste")
			(net "GND")
		)
		(pad "172" smd rect
			(at 2.050034 -40.375078 90)
			(size 0.519938 1.4986)
			(layers "F.Cu" "F.Mask" "F.Paste")
			(net "M_B_CPU0_SA_DQ<15>")
		)
		(pad "173" smd rect
			(at 2.050034 -39.52494 90)
			(size 0.519938 1.4986)
			(layers "F.Cu" "F.Mask" "F.Paste")
			(net "GND")
		)
		(pad "174" smd rect
			(at 2.050034 -38.675056 90)
			(size 0.519938 1.4986)
			(layers "F.Cu" "F.Mask" "F.Paste")
			(net "M_B_CPU0_SA_DQ<18>")
		)
		(pad "175" smd rect
			(at 2.050034 -37.824918 90)
			(size 0.519938 1.4986)
			(layers "F.Cu" "F.Mask" "F.Paste")
			(net "GND")
		)
		(pad "176" smd rect
			(at 2.050034 -36.975034 90)
			(size 0.519938 1.4986)
			(layers "F.Cu" "F.Mask" "F.Paste")
			(net "M_B_CPU0_SA_DQ<19>")
		)
		(pad "177" smd rect
			(at 2.050034 -36.124896 90)
			(size 0.519938 1.4986)
			(layers "F.Cu" "F.Mask" "F.Paste")
			(net "GND")
		)
		(pad "178" smd rect
			(at 2.050034 -35.275012 90)
			(size 0.519938 1.4986)
			(layers "F.Cu" "F.Mask" "F.Paste")
			(net "M_B_CPU0_SA_DQS_DN<7>")
		)
		(pad "179" smd rect
			(at 2.050034 -34.425128 90)
			(size 0.519938 1.4986)
			(layers "F.Cu" "F.Mask" "F.Paste")
			(net "M_B_CPU0_SA_DQS_DP<7>")
		)
		(pad "180" smd rect
			(at 2.050034 -33.57499 90)
			(size 0.519938 1.4986)
			(layers "F.Cu" "F.Mask" "F.Paste")
			(net "GND")
		)
		(pad "181" smd rect
			(at 2.050034 -32.725106 90)
			(size 0.519938 1.4986)
			(layers "F.Cu" "F.Mask" "F.Paste")
			(net "M_B_CPU0_SA_DQ<22>")
		)
		(pad "182" smd rect
			(at 2.050034 -31.874968 90)
			(size 0.519938 1.4986)
			(layers "F.Cu" "F.Mask" "F.Paste")
			(net "GND")
		)
		(pad "183" smd rect
			(at 2.050034 -31.025084 90)
			(size 0.519938 1.4986)
			(layers "F.Cu" "F.Mask" "F.Paste")
			(net "M_B_CPU0_SA_DQ<23>")
		)
		(pad "184" smd rect
			(at 2.050034 -30.174946 90)
			(size 0.519938 1.4986)
			(layers "F.Cu" "F.Mask" "F.Paste")
			(net "GND")
		)
		(pad "185" smd rect
			(at 2.050034 -29.325062 90)
			(size 0.519938 1.4986)
			(layers "F.Cu" "F.Mask" "F.Paste")
			(net "M_B_CPU0_SA_DQ<26>")
		)
		(pad "186" smd rect
			(at 2.050034 -28.474924 90)
			(size 0.519938 1.4986)
			(layers "F.Cu" "F.Mask" "F.Paste")
			(net "GND")
		)
		(pad "187" smd rect
			(at 2.050034 -27.62504 90)
			(size 0.519938 1.4986)
			(layers "F.Cu" "F.Mask" "F.Paste")
			(net "M_B_CPU0_SA_DQ<27>")
		)
		(pad "188" smd rect
			(at 2.050034 -26.774902 90)
			(size 0.519938 1.4986)
			(layers "F.Cu" "F.Mask" "F.Paste")
			(net "GND")
		)
		(pad "189" smd rect
			(at 2.050034 -25.925018 90)
			(size 0.519938 1.4986)
			(layers "F.Cu" "F.Mask" "F.Paste")
			(net "M_B_CPU0_SA_DQS_DN<8>")
		)
		(pad "190" smd rect
			(at 2.050034 -25.07488 90)
			(size 0.519938 1.4986)
			(layers "F.Cu" "F.Mask" "F.Paste")
			(net "M_B_CPU0_SA_DQS_DP<8>")
		)
		(pad "191" smd rect
			(at 2.050034 -24.224996 90)
			(size 0.519938 1.4986)
			(layers "F.Cu" "F.Mask" "F.Paste")
			(net "GND")
		)
		(pad "192" smd rect
			(at 2.050034 -23.375112 90)
			(size 0.519938 1.4986)
			(layers "F.Cu" "F.Mask" "F.Paste")
			(net "M_B_CPU0_SA_DQ<30>")
		)
		(pad "193" smd rect
			(at 2.050034 -22.524974 90)
			(size 0.519938 1.4986)
			(layers "F.Cu" "F.Mask" "F.Paste")
			(net "GND")
		)
		(pad "194" smd rect
			(at 2.050034 -21.67509 90)
			(size 0.519938 1.4986)
			(layers "F.Cu" "F.Mask" "F.Paste")
			(net "M_B_CPU0_SA_DQ<31>")
		)
		(pad "195" smd rect
			(at 2.050034 -20.824952 90)
			(size 0.519938 1.4986)
			(layers "F.Cu" "F.Mask" "F.Paste")
			(net "GND")
		)
		(pad "196" smd rect
			(at 2.050034 -19.975068 90)
			(size 0.519938 1.4986)
			(layers "F.Cu" "F.Mask" "F.Paste")
			(net "M_B_CPU0_SA_CB<2>")
		)
		(pad "197" smd rect
			(at 2.050034 -19.12493 90)
			(size 0.519938 1.4986)
			(layers "F.Cu" "F.Mask" "F.Paste")
			(net "GND")
		)
		(pad "198" smd rect
			(at 2.050034 -18.275046 90)
			(size 0.519938 1.4986)
			(layers "F.Cu" "F.Mask" "F.Paste")
			(net "M_B_CPU0_SA_CB<3>")
		)
		(pad "199" smd rect
			(at 2.050034 -17.424908 90)
			(size 0.519938 1.4986)
			(layers "F.Cu" "F.Mask" "F.Paste")
			(net "GND")
		)
		(pad "200" smd rect
			(at 2.050034 -16.575024 90)
			(size 0.519938 1.4986)
			(layers "F.Cu" "F.Mask" "F.Paste")
			(net "M_B_CPU0_SA_DQS_DN<9>")
		)
		(pad "201" smd rect
			(at 2.050034 -15.724886 90)
			(size 0.519938 1.4986)
			(layers "F.Cu" "F.Mask" "F.Paste")
			(net "M_B_CPU0_SA_DQS_DP<9>")
		)
		(pad "202" smd rect
			(at 2.050034 -14.875002 90)
			(size 0.519938 1.4986)
			(layers "F.Cu" "F.Mask" "F.Paste")
			(net "GND")
		)
		(pad "203" smd rect
			(at 2.050034 -14.025118 90)
			(size 0.519938 1.4986)
			(layers "F.Cu" "F.Mask" "F.Paste")
			(net "M_B_CPU0_SA_CB<6>")
		)
		(pad "204" smd rect
			(at 2.050034 -13.17498 90)
			(size 0.519938 1.4986)
			(layers "F.Cu" "F.Mask" "F.Paste")
			(net "GND")
		)
		(pad "205" smd rect
			(at 2.050034 -12.325096 90)
			(size 0.519938 1.4986)
			(layers "F.Cu" "F.Mask" "F.Paste")
			(net "M_B_CPU0_SA_CB<7>")
		)
		(pad "206" smd rect
			(at 2.050034 -11.474958 90)
			(size 0.519938 1.4986)
			(layers "F.Cu" "F.Mask" "F.Paste")
			(net "GND")
		)
		(pad "207" smd rect
			(at 2.050034 -10.625074 90)
			(size 0.519938 1.4986)
			(layers "F.Cu" "F.Mask" "F.Paste")
			(net "M_B_CPU0_RESET_N")
		)
		(pad "208" smd rect
			(at 2.050034 -9.774936 90)
			(size 0.519938 1.4986)
			(layers "F.Cu" "F.Mask" "F.Paste")
			(net "GND")
		)
		(pad "209" smd rect
			(at 2.050034 -8.925052 90)
			(size 0.519938 1.4986)
			(layers "F.Cu" "F.Mask" "F.Paste")
			(net "M_B_CPU0_SA_CS_N<1>")
		)
		(pad "210" smd rect
			(at 2.050034 -8.074914 90)
			(size 0.519938 1.4986)
			(layers "F.Cu" "F.Mask" "F.Paste")
			(net "GND")
		)
		(pad "211" smd rect
			(at 2.050034 -7.22503 90)
			(size 0.519938 1.4986)
			(layers "F.Cu" "F.Mask" "F.Paste")
			(net "M_B_CPU0_SA_CA<1>")
		)
		(pad "212" smd rect
			(at 2.050034 -6.374892 90)
			(size 0.519938 1.4986)
			(layers "F.Cu" "F.Mask" "F.Paste")
			(net "GND")
		)
		(pad "213" smd rect
			(at 2.050034 -5.525008 90)
			(size 0.519938 1.4986)
			(layers "F.Cu" "F.Mask" "F.Paste")
			(net "M_B_CPU0_SA_CA<3>")
		)
		(pad "214" smd rect
			(at 2.050034 -4.675124 90)
			(size 0.519938 1.4986)
			(layers "F.Cu" "F.Mask" "F.Paste")
			(net "GND")
		)
		(pad "215" smd rect
			(at 2.050034 -3.824986 90)
			(size 0.519938 1.4986)
			(layers "F.Cu" "F.Mask" "F.Paste")
			(net "M_B_CPU0_SA_CA<5>")
		)
		(pad "216" smd rect
			(at 2.050034 -2.975102 90)
			(size 0.519938 1.4986)
			(layers "F.Cu" "F.Mask" "F.Paste")
			(net "GND")
		)
		(pad "217" smd rect
			(at 2.050034 -2.124964 90)
			(size 0.519938 1.4986)
			(layers "F.Cu" "F.Mask" "F.Paste")
			(net "M_B_CPU0_CLK_DP<0>")
		)
		(pad "218" smd rect
			(at 2.050034 -1.27508 90)
			(size 0.519938 1.4986)
			(layers "F.Cu" "F.Mask" "F.Paste")
			(net "M_B_CPU0_CLK_DN<0>")
		)
		(pad "219" smd rect
			(at 2.050034 -0.424942 90)
			(size 0.519938 1.4986)
			(layers "F.Cu" "F.Mask" "F.Paste")
			(net "GND")
		)
		(pad "220" smd rect
			(at 2.050034 5.525008 90)
			(size 0.519938 1.4986)
			(layers "F.Cu" "F.Mask" "F.Paste")
			(net "Net_2267")
		)
		(pad "221" smd rect
			(at 2.050034 6.374892 90)
			(size 0.519938 1.4986)
			(layers "F.Cu" "F.Mask" "F.Paste")
			(net "M_B_CPU0_SB_CA<1>")
		)
		(pad "222" smd rect
			(at 2.050034 7.22503 90)
			(size 0.519938 1.4986)
			(layers "F.Cu" "F.Mask" "F.Paste")
			(net "GND")
		)
		(pad "223" smd rect
			(at 2.050034 8.074914 90)
			(size 0.519938 1.4986)
			(layers "F.Cu" "F.Mask" "F.Paste")
			(net "M_B_CPU0_SB_CA<3>")
		)
		(pad "224" smd rect
			(at 2.050034 8.925052 90)
			(size 0.519938 1.4986)
			(layers "F.Cu" "F.Mask" "F.Paste")
			(net "GND")
		)
		(pad "225" smd rect
			(at 2.050034 9.774936 90)
			(size 0.519938 1.4986)
			(layers "F.Cu" "F.Mask" "F.Paste")
			(net "M_B_CPU0_SB_CA<5>")
		)
		(pad "226" smd rect
			(at 2.050034 10.625074 90)
			(size 0.519938 1.4986)
			(layers "F.Cu" "F.Mask" "F.Paste")
			(net "GND")
		)
	)
)
